(kicad_pcb
	(version 20260206)
	(generator "pcbnew")
	(generator_version "10.0")
	(general
		(thickness 1.6)
		(legacy_teardrops no)
	)
	(paper "A4")
	(title_block
		(title "03242023_DA0F0TMBIJ0_F0T_Motherboard_J_brd_V01_OCP.brd")
		(comment 1 "Grand Teton / footprint 3039 of 6105 (U2), pads 106-210 of 4677")
	)
	(layers
		(0 "F.Cu" signal "TOP")
		(4 "In1.Cu" signal "GND")
		(6 "In2.Cu" signal "IN1")
		(8 "In3.Cu" signal "GND1")
		(10 "In4.Cu" signal "IN2")
		(12 "In5.Cu" signal "GND2")
		(14 "In6.Cu" signal "IN3")
		(16 "In7.Cu" signal "GND3")
		(18 "In8.Cu" signal "VCC")
		(20 "In9.Cu" signal "VCC1")
		(22 "In10.Cu" signal "GND4")
		(24 "In11.Cu" signal "IN4")
		(26 "In12.Cu" signal "GND5")
		(28 "In13.Cu" signal "IN5")
		(30 "In14.Cu" signal "GND6")
		(32 "In15.Cu" signal "IN6")
		(34 "In16.Cu" signal "GND7")
		(2 "B.Cu" signal "BOTTOM")
		(9 "F.Adhes" user "F.Adhesive")
		(11 "B.Adhes" user "B.Adhesive")
		(13 "F.Paste" user "Package Geometry/Pastemask Top")
		(15 "B.Paste" user "Package Geometry/Pastemask Bottom")
		(5 "F.SilkS" user "Ref Des/Silkscreen Top")
		(7 "B.SilkS" user "Ref Des/Silkscreen Bottom")
		(1 "F.Mask" user "Board Geometry/Soldermask Top")
		(3 "B.Mask" user "Board Geometry/Soldermask Bottom")
		(17 "Dwgs.User" user "User.Drawings")
		(19 "Cmts.User" user "User.Comments")
		(21 "Eco1.User" user "User.Eco1")
		(23 "Eco2.User" user "User.Eco2")
		(25 "Edge.Cuts" user "Board Geometry/Outline")
		(27 "Margin" user)
		(31 "F.CrtYd" user "Package Geometry/Place Bound Top")
		(29 "B.CrtYd" user "Package Geometry/Place Bound Bottom")
		(35 "F.Fab" user "Ref Des/Assembly Top")
		(33 "B.Fab" user "Ref Des/Assembly Bottom")
	)
	(footprint ""
		(layer "F.Cu")
		(at 359.870248 -251.76988 90)
		(property "Reference" "U2"
			(at -74.416158 -44.488608 0)
			(unlocked yes)
			(layer "F.SilkS")
			(effects
				(font
					(size 1.6002 1.1938)
					(thickness 0.1524)
				)
				(justify left)
			)
		)
		(property "Value" ""
			(at 0 0 90)
			(layer "F.Fab")
			(effects
				(font
					(size 1.27 1.27)
				)
			)
		)
		(duplicate_pad_numbers_are_jumpers no)
		(pad "AB71" smd circle
			(at 21.147278 -17.096486 270)
			(size 0.4318 0.4318)
			(layers "F.Cu" "F.Mask" "F.Paste")
			(net "GND")
		)
		(pad "AB73" smd circle
			(at 22.77491 -17.096486 270)
			(size 0.4318 0.4318)
			(layers "F.Cu" "F.Mask" "F.Paste")
			(net "M_D_CPU0_SA_DQS_DN<0>")
		)
		(pad "AB75" smd circle
			(at 24.402796 -17.096486 270)
			(size 0.4318 0.4318)
			(layers "F.Cu" "F.Mask" "F.Paste")
			(net "GND")
		)
		(pad "AB77" smd circle
			(at 26.030682 -17.096486 270)
			(size 0.4318 0.4318)
			(layers "F.Cu" "F.Mask" "F.Paste")
			(net "GND")
		)
		(pad "AB79" smd circle
			(at 27.658314 -17.096486 270)
			(size 0.4318 0.4318)
			(layers "F.Cu" "F.Mask" "F.Paste")
			(net "GND")
		)
		(pad "AB81" smd circle
			(at 29.2862 -17.096486 270)
			(size 0.4318 0.4318)
			(layers "F.Cu" "F.Mask" "F.Paste")
			(net "GND")
		)
		(pad "AB83" smd circle
			(at 30.914086 -17.096486 270)
			(size 0.4318 0.4318)
			(layers "F.Cu" "F.Mask" "F.Paste")
			(net "GND")
		)
		(pad "AB85" smd circle
			(at 32.541718 -17.096486 270)
			(size 0.4318 0.4318)
			(layers "F.Cu" "F.Mask" "F.Paste")
			(net "P5E_CPU0_PE4_TX_DP<5>")
		)
		(pad "AB87" smd circle
			(at 34.169604 -17.096486 270)
			(size 0.4318 0.4318)
			(layers "F.Cu" "F.Mask" "F.Paste")
			(net "GND")
		)
		(pad "AB89" smd circle
			(at 35.797236 -17.096486 270)
			(size 0.4318 0.4318)
			(layers "F.Cu" "F.Mask" "F.Paste")
			(net "P5E_CPU0_PE4_RX_DN<5>")
		)
		(pad "AB91" smd oval
			(at 37.425122 -17.096486)
			(size 0.381 0.4826)
			(drill
				(offset 0 -0.0508)
			)
			(layers "F.Cu" "F.Mask" "F.Paste")
			(net "GND")
		)
		(pad "AC1" smd oval
			(at -37.425122 -16.736314 180)
			(size 0.381 0.4826)
			(drill
				(offset 0 -0.0508)
			)
			(layers "F.Cu" "F.Mask" "F.Paste")
			(net "GND")
		)
		(pad "AC3" smd circle
			(at -35.797236 -16.736314 270)
			(size 0.4318 0.4318)
			(layers "F.Cu" "F.Mask" "F.Paste")
			(net "UPI_CPU0_CPU1_P0P1_DP<7>")
		)
		(pad "AC5" smd circle
			(at -34.169604 -16.736314 270)
			(size 0.4318 0.4318)
			(layers "F.Cu" "F.Mask" "F.Paste")
			(net "GND")
		)
		(pad "AC7" smd circle
			(at -32.541718 -16.736314 270)
			(size 0.4318 0.4318)
			(layers "F.Cu" "F.Mask" "F.Paste")
			(net "UPI_CPU1_CPU0_P1P0_DP<6>")
		)
		(pad "AC9" smd circle
			(at -30.914086 -16.736314 270)
			(size 0.4318 0.4318)
			(layers "F.Cu" "F.Mask" "F.Paste")
			(net "GND")
		)
		(pad "AC11" smd circle
			(at -29.2862 -16.736314 270)
			(size 0.4318 0.4318)
			(layers "F.Cu" "F.Mask" "F.Paste")
			(net "P5E_CPU0_PE0_RX_DP<6>")
		)
		(pad "AC13" smd circle
			(at -27.658314 -16.736314 270)
			(size 0.4318 0.4318)
			(layers "F.Cu" "F.Mask" "F.Paste")
			(net "GND")
		)
		(pad "AC15" smd circle
			(at -26.030682 -16.736314 270)
			(size 0.4318 0.4318)
			(layers "F.Cu" "F.Mask" "F.Paste")
			(net "P5E_CPU0_PE0_TX_DP<5>")
		)
		(pad "AC17" smd circle
			(at -24.402796 -16.736314 270)
			(size 0.4318 0.4318)
			(layers "F.Cu" "F.Mask" "F.Paste")
			(net "M_C_CPU0_SB_DQ<30>")
		)
		(pad "AC19" smd circle
			(at -22.77491 -16.736314 270)
			(size 0.4318 0.4318)
			(layers "F.Cu" "F.Mask" "F.Paste")
			(net "M_C_CPU0_SB_DQ<25>")
		)
		(pad "AC21" smd circle
			(at -21.147278 -16.736314 270)
			(size 0.4318 0.4318)
			(layers "F.Cu" "F.Mask" "F.Paste")
			(net "GND")
		)
		(pad "AC23" smd circle
			(at -19.519392 -16.736314 270)
			(size 0.4318 0.4318)
			(layers "F.Cu" "F.Mask" "F.Paste")
			(net "M_D_CPU0_SB_DQ<20>")
		)
		(pad "AC25" smd circle
			(at -17.89176 -16.736314 270)
			(size 0.4318 0.4318)
			(layers "F.Cu" "F.Mask" "F.Paste")
			(net "M_D_CPU0_SB_DQ<17>")
		)
		(pad "AC27" smd circle
			(at -16.263874 -16.736314 270)
			(size 0.4318 0.4318)
			(layers "F.Cu" "F.Mask" "F.Paste")
			(net "GND")
		)
		(pad "AC29" smd circle
			(at -14.635988 -16.736314 270)
			(size 0.4318 0.4318)
			(layers "F.Cu" "F.Mask" "F.Paste")
			(net "M_C_CPU0_SB_DQ<12>")
		)
		(pad "AC31" smd circle
			(at -13.008356 -16.736314 270)
			(size 0.4318 0.4318)
			(layers "F.Cu" "F.Mask" "F.Paste")
			(net "M_C_CPU0_SB_DQ<9>")
		)
		(pad "AC33" smd circle
			(at -11.380724 -16.736314 270)
			(size 0.4318 0.4318)
			(layers "F.Cu" "F.Mask" "F.Paste")
			(net "GND")
		)
		(pad "AC35" smd circle
			(at -9.752838 -16.736314 270)
			(size 0.4318 0.4318)
			(layers "F.Cu" "F.Mask" "F.Paste")
			(net "M_C_CPU0_SB_DQ<4>")
		)
		(pad "AC37" smd circle
			(at -8.124952 -16.736314 270)
			(size 0.4318 0.4318)
			(layers "F.Cu" "F.Mask" "F.Paste")
			(net "M_C_CPU0_SB_DQ<1>")
		)
		(pad "AC39" smd circle
			(at -6.49732 -16.736314 270)
			(size 0.4318 0.4318)
			(layers "F.Cu" "F.Mask" "F.Paste")
			(net "GND")
		)
		(pad "AC41" smd circle
			(at -4.869434 -16.736314 270)
			(size 0.4318 0.4318)
			(layers "F.Cu" "F.Mask" "F.Paste")
			(net "M_D_CPU0_SB_CS_N<0>")
		)
		(pad "AC43" smd circle
			(at -3.241802 -16.736314 270)
			(size 0.4318 0.4318)
			(layers "F.Cu" "F.Mask" "F.Paste")
			(net "M_D_CPU0_SB_CA<4>")
		)
		(pad "AC45" smd circle
			(at -1.613916 -16.736314 270)
			(size 0.4318 0.4318)
			(layers "F.Cu" "F.Mask" "F.Paste")
			(net "GND")
		)
		(pad "AC48" smd circle
			(at 2.427732 -16.626332 270)
			(size 0.4318 0.4318)
			(layers "F.Cu" "F.Mask" "F.Paste")
			(net "M_C_CPU0_SA_RSP<0>")
		)
		(pad "AC50" smd circle
			(at 4.055618 -16.626332 270)
			(size 0.4318 0.4318)
			(layers "F.Cu" "F.Mask" "F.Paste")
			(net "M_D_CPU0_SA_RSP<1>")
		)
		(pad "AC52" smd circle
			(at 5.68325 -16.626332 270)
			(size 0.4318 0.4318)
			(layers "F.Cu" "F.Mask" "F.Paste")
			(net "GND")
		)
		(pad "AC54" smd circle
			(at 7.311136 -16.626332 270)
			(size 0.4318 0.4318)
			(layers "F.Cu" "F.Mask" "F.Paste")
			(net "M_C_CPU0_SA_CB<4>")
		)
		(pad "AC56" smd circle
			(at 8.939022 -16.626332 270)
			(size 0.4318 0.4318)
			(layers "F.Cu" "F.Mask" "F.Paste")
			(net "M_C_CPU0_SA_CB<1>")
		)
		(pad "AC58" smd circle
			(at 10.566654 -16.626332 270)
			(size 0.4318 0.4318)
			(layers "F.Cu" "F.Mask" "F.Paste")
			(net "GND")
		)
		(pad "AC60" smd circle
			(at 12.19454 -16.626332 270)
			(size 0.4318 0.4318)
			(layers "F.Cu" "F.Mask" "F.Paste")
			(net "M_C_CPU0_SA_DQ<28>")
		)
		(pad "AC62" smd circle
			(at 13.822426 -16.626332 270)
			(size 0.4318 0.4318)
			(layers "F.Cu" "F.Mask" "F.Paste")
			(net "M_C_CPU0_SA_DQ<25>")
		)
		(pad "AC64" smd circle
			(at 15.450058 -16.626332 270)
			(size 0.4318 0.4318)
			(layers "F.Cu" "F.Mask" "F.Paste")
			(net "GND")
		)
		(pad "AC66" smd circle
			(at 17.07769 -16.626332 270)
			(size 0.4318 0.4318)
			(layers "F.Cu" "F.Mask" "F.Paste")
			(net "M_C_CPU0_SA_DQ<12>")
		)
		(pad "AC68" smd circle
			(at 18.705576 -16.626332 270)
			(size 0.4318 0.4318)
			(layers "F.Cu" "F.Mask" "F.Paste")
			(net "M_C_CPU0_SA_DQ<9>")
		)
		(pad "AC70" smd circle
			(at 20.333462 -16.626332 270)
			(size 0.4318 0.4318)
			(layers "F.Cu" "F.Mask" "F.Paste")
			(net "GND")
		)
		(pad "AC72" smd circle
			(at 21.961094 -16.626332 270)
			(size 0.4318 0.4318)
			(layers "F.Cu" "F.Mask" "F.Paste")
			(net "M_D_CPU0_SA_DQ<4>")
		)
		(pad "AC74" smd circle
			(at 23.58898 -16.626332 270)
			(size 0.4318 0.4318)
			(layers "F.Cu" "F.Mask" "F.Paste")
			(net "M_D_CPU0_SA_DQ<1>")
		)
		(pad "AC76" smd circle
			(at 25.216612 -16.626332 270)
			(size 0.4318 0.4318)
			(layers "F.Cu" "F.Mask" "F.Paste")
			(net "GND")
		)
		(pad "AC78" smd circle
			(at 26.844498 -16.626332 270)
			(size 0.4318 0.4318)
			(layers "F.Cu" "F.Mask" "F.Paste")
			(net "NC_CPU0_HBM2_VIEWDIG0")
		)
		(pad "AC80" smd circle
			(at 28.472384 -16.626332 270)
			(size 0.4318 0.4318)
			(layers "F.Cu" "F.Mask" "F.Paste")
			(net "UPI_CPU1_CPU0_P2P2_DN<17>")
		)
		(pad "AC82" smd circle
			(at 30.100016 -16.626332 270)
			(size 0.4318 0.4318)
			(layers "F.Cu" "F.Mask" "F.Paste")
			(net "UPI_CPU1_CPU0_P2P2_DN<16>")
		)
		(pad "AC84" smd circle
			(at 31.727902 -16.626332 270)
			(size 0.4318 0.4318)
			(layers "F.Cu" "F.Mask" "F.Paste")
			(net "GND")
		)
		(pad "AC86" smd circle
			(at 33.355534 -16.626332 270)
			(size 0.4318 0.4318)
			(layers "F.Cu" "F.Mask" "F.Paste")
			(net "P5E_CPU0_PE4_TX_DN<6>")
		)
		(pad "AC88" smd circle
			(at 34.98342 -16.626332 270)
			(size 0.4318 0.4318)
			(layers "F.Cu" "F.Mask" "F.Paste")
			(net "GND")
		)
		(pad "AC90" smd circle
			(at 36.611306 -16.626332 270)
			(size 0.4318 0.4318)
			(layers "F.Cu" "F.Mask" "F.Paste")
			(net "P5E_CPU0_PE4_RX_DP<6>")
		)
		(pad "AD2" smd circle
			(at -36.611306 -16.266668 270)
			(size 0.4318 0.4318)
			(layers "F.Cu" "F.Mask" "F.Paste")
			(net "UPI_CPU0_CPU1_P0P1_DN<7>")
		)
		(pad "AD4" smd circle
			(at -34.98342 -16.266668 270)
			(size 0.4318 0.4318)
			(layers "F.Cu" "F.Mask" "F.Paste")
			(net "GND")
		)
		(pad "AD6" smd circle
			(at -33.355534 -16.266668 270)
			(size 0.4318 0.4318)
			(layers "F.Cu" "F.Mask" "F.Paste")
			(net "UPI_CPU1_CPU0_P1P0_DP<7>")
		)
		(pad "AD8" smd circle
			(at -31.727902 -16.266668 270)
			(size 0.4318 0.4318)
			(layers "F.Cu" "F.Mask" "F.Paste")
			(net "GND")
		)
		(pad "AD10" smd circle
			(at -30.100016 -16.266668 270)
			(size 0.4318 0.4318)
			(layers "F.Cu" "F.Mask" "F.Paste")
			(net "P5E_CPU0_PE0_RX_DP<7>")
		)
		(pad "AD12" smd circle
			(at -28.472384 -16.266668 270)
			(size 0.4318 0.4318)
			(layers "F.Cu" "F.Mask" "F.Paste")
			(net "GND")
		)
		(pad "AD14" smd circle
			(at -26.844498 -16.266668 270)
			(size 0.4318 0.4318)
			(layers "F.Cu" "F.Mask" "F.Paste")
			(net "P5E_CPU0_PE0_TX_DP<6>")
		)
		(pad "AD16" smd circle
			(at -25.216612 -16.266668 270)
			(size 0.4318 0.4318)
			(layers "F.Cu" "F.Mask" "F.Paste")
			(net "GND")
		)
		(pad "AD18" smd circle
			(at -23.58898 -16.266668 270)
			(size 0.4318 0.4318)
			(layers "F.Cu" "F.Mask" "F.Paste")
			(net "M_C_CPU0_SB_DQS_DP<3>")
		)
		(pad "AD20" smd circle
			(at -21.961094 -16.266668 270)
			(size 0.4318 0.4318)
			(layers "F.Cu" "F.Mask" "F.Paste")
			(net "M_C_CPU0_SB_DQ<24>")
		)
		(pad "AD22" smd circle
			(at -20.333462 -16.266668 270)
			(size 0.4318 0.4318)
			(layers "F.Cu" "F.Mask" "F.Paste")
			(net "M_D_CPU0_SB_DQ<21>")
		)
		(pad "AD24" smd circle
			(at -18.705576 -16.266668 270)
			(size 0.4318 0.4318)
			(layers "F.Cu" "F.Mask" "F.Paste")
			(net "M_D_CPU0_SB_DQS_DP<2>")
		)
		(pad "AD26" smd circle
			(at -17.07769 -16.266668 270)
			(size 0.4318 0.4318)
			(layers "F.Cu" "F.Mask" "F.Paste")
			(net "M_D_CPU0_SB_DQ<16>")
		)
		(pad "AD28" smd circle
			(at -15.450058 -16.266668 270)
			(size 0.4318 0.4318)
			(layers "F.Cu" "F.Mask" "F.Paste")
			(net "M_C_CPU0_SB_DQ<13>")
		)
		(pad "AD30" smd circle
			(at -13.822426 -16.266668 270)
			(size 0.4318 0.4318)
			(layers "F.Cu" "F.Mask" "F.Paste")
			(net "M_C_CPU0_SB_DQS_DP<1>")
		)
		(pad "AD32" smd circle
			(at -12.19454 -16.266668 270)
			(size 0.4318 0.4318)
			(layers "F.Cu" "F.Mask" "F.Paste")
			(net "M_C_CPU0_SB_DQ<8>")
		)
		(pad "AD34" smd circle
			(at -10.566654 -16.266668 270)
			(size 0.4318 0.4318)
			(layers "F.Cu" "F.Mask" "F.Paste")
			(net "M_C_CPU0_SB_DQ<5>")
		)
		(pad "AD36" smd circle
			(at -8.939022 -16.266668 270)
			(size 0.4318 0.4318)
			(layers "F.Cu" "F.Mask" "F.Paste")
			(net "M_C_CPU0_SB_DQS_DP<0>")
		)
		(pad "AD38" smd circle
			(at -7.311136 -16.266668 270)
			(size 0.4318 0.4318)
			(layers "F.Cu" "F.Mask" "F.Paste")
			(net "M_C_CPU0_SB_DQ<0>")
		)
		(pad "AD40" smd circle
			(at -5.68325 -16.266668 270)
			(size 0.4318 0.4318)
			(layers "F.Cu" "F.Mask" "F.Paste")
			(net "M_D_CPU0_SB_CS_N<3>")
		)
		(pad "AD42" smd circle
			(at -4.055618 -16.266668 270)
			(size 0.4318 0.4318)
			(layers "F.Cu" "F.Mask" "F.Paste")
			(net "GND")
		)
		(pad "AD44" smd circle
			(at -2.427732 -16.266668 270)
			(size 0.4318 0.4318)
			(layers "F.Cu" "F.Mask" "F.Paste")
			(net "M_D_CPU0_SB_CA<2>")
		)
		(pad "AD47" smd circle
			(at 1.613916 -16.156686 270)
			(size 0.4318 0.4318)
			(layers "F.Cu" "F.Mask" "F.Paste")
			(net "M_C_CPU0_SA_RSP<1>")
		)
		(pad "AD49" smd circle
			(at 3.241802 -16.156686 270)
			(size 0.4318 0.4318)
			(layers "F.Cu" "F.Mask" "F.Paste")
			(net "M_C_CPU0_CLK_DP<0>")
		)
		(pad "AD51" smd circle
			(at 4.869434 -16.156686 270)
			(size 0.4318 0.4318)
			(layers "F.Cu" "F.Mask" "F.Paste")
			(net "M_D_CPU0_SA_RSP<0>")
		)
		(pad "AD53" smd circle
			(at 6.49732 -16.156686 270)
			(size 0.4318 0.4318)
			(layers "F.Cu" "F.Mask" "F.Paste")
			(net "M_C_CPU0_SA_CB<5>")
		)
		(pad "AD55" smd circle
			(at 8.124952 -16.156686 270)
			(size 0.4318 0.4318)
			(layers "F.Cu" "F.Mask" "F.Paste")
			(net "M_C_CPU0_SA_DQS_DN<4>")
		)
		(pad "AD57" smd circle
			(at 9.752838 -16.156686 270)
			(size 0.4318 0.4318)
			(layers "F.Cu" "F.Mask" "F.Paste")
			(net "M_C_CPU0_SA_CB<0>")
		)
		(pad "AD59" smd circle
			(at 11.380724 -16.156686 270)
			(size 0.4318 0.4318)
			(layers "F.Cu" "F.Mask" "F.Paste")
			(net "M_C_CPU0_SA_DQ<29>")
		)
		(pad "AD61" smd circle
			(at 13.008356 -16.156686 270)
			(size 0.4318 0.4318)
			(layers "F.Cu" "F.Mask" "F.Paste")
			(net "M_C_CPU0_SA_DQS_DP<3>")
		)
		(pad "AD63" smd circle
			(at 14.635988 -16.156686 270)
			(size 0.4318 0.4318)
			(layers "F.Cu" "F.Mask" "F.Paste")
			(net "M_C_CPU0_SA_DQ<24>")
		)
		(pad "AD65" smd circle
			(at 16.263874 -16.156686 270)
			(size 0.4318 0.4318)
			(layers "F.Cu" "F.Mask" "F.Paste")
			(net "M_C_CPU0_SA_DQ<13>")
		)
		(pad "AD67" smd circle
			(at 17.89176 -16.156686 270)
			(size 0.4318 0.4318)
			(layers "F.Cu" "F.Mask" "F.Paste")
			(net "M_C_CPU0_SA_DQS_DP<1>")
		)
		(pad "AD69" smd circle
			(at 19.519392 -16.156686 270)
			(size 0.4318 0.4318)
			(layers "F.Cu" "F.Mask" "F.Paste")
			(net "M_C_CPU0_SA_DQ<8>")
		)
		(pad "AD71" smd circle
			(at 21.147278 -16.156686 270)
			(size 0.4318 0.4318)
			(layers "F.Cu" "F.Mask" "F.Paste")
			(net "M_D_CPU0_SA_DQ<5>")
		)
		(pad "AD73" smd circle
			(at 22.77491 -16.156686 270)
			(size 0.4318 0.4318)
			(layers "F.Cu" "F.Mask" "F.Paste")
			(net "M_D_CPU0_SA_DQS_DP<0>")
		)
		(pad "AD75" smd circle
			(at 24.402796 -16.156686 270)
			(size 0.4318 0.4318)
			(layers "F.Cu" "F.Mask" "F.Paste")
			(net "M_D_CPU0_SA_DQ<0>")
		)
		(pad "AD77" smd circle
			(at 26.030682 -16.156686 270)
			(size 0.4318 0.4318)
			(layers "F.Cu" "F.Mask" "F.Paste")
			(net "NC_CPU0_HBM2_VIEWDIG1")
		)
		(pad "AD79" smd circle
			(at 27.658314 -16.156686 270)
			(size 0.4318 0.4318)
			(layers "F.Cu" "F.Mask" "F.Paste")
			(net "GND")
		)
		(pad "AD81" smd circle
			(at 29.2862 -16.156686 270)
			(size 0.4318 0.4318)
			(layers "F.Cu" "F.Mask" "F.Paste")
			(net "UPI_CPU1_CPU0_P2P2_DP<16>")
		)
		(pad "AD83" smd circle
			(at 30.914086 -16.156686 270)
			(size 0.4318 0.4318)
			(layers "F.Cu" "F.Mask" "F.Paste")
			(net "GND")
		)
		(pad "AD85" smd circle
			(at 32.541718 -16.156686 270)
			(size 0.4318 0.4318)
			(layers "F.Cu" "F.Mask" "F.Paste")
			(net "PVCCFA_EHV_FIVRA_CPU0")
		)
		(pad "AD87" smd circle
			(at 34.169604 -16.156686 270)
			(size 0.4318 0.4318)
			(layers "F.Cu" "F.Mask" "F.Paste")
			(net "P5E_CPU0_PE4_TX_DP<6>")
		)
		(pad "AD89" smd circle
			(at 35.797236 -16.156686 270)
			(size 0.4318 0.4318)
			(layers "F.Cu" "F.Mask" "F.Paste")
			(net "PVCCFA_EHV_FIVRA_CPU0")
		)
		(pad "AD91" smd oval
			(at 37.425122 -16.156686)
			(size 0.381 0.4826)
			(drill
				(offset 0 -0.0508)
			)
			(layers "F.Cu" "F.Mask" "F.Paste")
			(net "P5E_CPU0_PE4_RX_DN<6>")
		)
		(pad "AE1" smd oval
			(at -37.425122 -15.796514 180)
			(size 0.381 0.4826)
			(drill
				(offset 0 -0.0508)
			)
			(layers "F.Cu" "F.Mask" "F.Paste")
			(net "UPI_CPU0_CPU1_P0P1_DP<8>")
		)
		(pad "AE3" smd circle
			(at -35.797236 -15.796514 270)
			(size 0.4318 0.4318)
			(layers "F.Cu" "F.Mask" "F.Paste")
			(net "PVCCFA_EHV_CPU0")
		)
		(pad "AE5" smd circle
			(at -34.169604 -15.796514 270)
			(size 0.4318 0.4318)
			(layers "F.Cu" "F.Mask" "F.Paste")
			(net "UPI_CPU1_CPU0_P1P0_DN<7>")
		)
		(pad "AE7" smd circle
			(at -32.541718 -15.796514 270)
			(size 0.4318 0.4318)
			(layers "F.Cu" "F.Mask" "F.Paste")
			(net "PVCCFA_EHV_FIVRA_CPU0")
		)
	)
)
